(kicad_pcb
	(version 20260206)
	(generator "pcbnew")
	(generator_version "10.0")
	(general
		(thickness 1.6)
		(legacy_teardrops no)
	)
	(paper "A4")
	(title_block
		(title "04192023_DAF0TMB3IC0_F0TG_MB_C_brd_V02_OCP.brd")
		(comment 1 "Grand Teton / footprints 2541-2548 of 8354")
	)
	(layers
		(0 "F.Cu" signal "TOP")
		(4 "In1.Cu" signal "GND")
		(6 "In2.Cu" signal "IN1")
		(8 "In3.Cu" signal "GND1")
		(10 "In4.Cu" signal "IN2")
		(12 "In5.Cu" signal "GND2")
		(14 "In6.Cu" signal "IN3")
		(16 "In7.Cu" signal "GND3")
		(18 "In8.Cu" signal "VCC")
		(20 "In9.Cu" signal "VCC1")
		(22 "In10.Cu" signal "GND4")
		(24 "In11.Cu" signal "IN4")
		(26 "In12.Cu" signal "GND5")
		(28 "In13.Cu" signal "IN5")
		(30 "In14.Cu" signal "GND6")
		(32 "In15.Cu" signal "IN6")
		(34 "In16.Cu" signal "GND7")
		(2 "B.Cu" signal "BOTTOM")
		(9 "F.Adhes" user "F.Adhesive")
		(11 "B.Adhes" user "B.Adhesive")
		(13 "F.Paste" user "Package Geometry/Pastemask Top")
		(15 "B.Paste" user "Package Geometry/Pastemask Bottom")
		(5 "F.SilkS" user "Ref Des/Silkscreen Top")
		(7 "B.SilkS" user "Ref Des/Silkscreen Bottom")
		(1 "F.Mask" user "Board Geometry/Soldermask Top")
		(3 "B.Mask" user "Board Geometry/Soldermask Bottom")
		(17 "Dwgs.User" user "User.Drawings")
		(19 "Cmts.User" user "User.Comments")
		(21 "Eco1.User" user "User.Eco1")
		(23 "Eco2.User" user "User.Eco2")
		(25 "Edge.Cuts" user "Board Geometry/Outline")
		(27 "Margin" user)
		(31 "F.CrtYd" user "Package Geometry/Place Bound Top")
		(29 "B.CrtYd" user "Package Geometry/Place Bound Bottom")
		(35 "F.Fab" user "Ref Des/Assembly Top")
		(33 "B.Fab" user "Ref Des/Assembly Bottom")
	)
	(footprint ""
		(layer "F.Cu")
		(at 79.114904 -395.221206 -90)
		(property "Reference" "R792"
			(at 0 0 270)
			(layer "F.SilkS")
			(hide yes)
			(effects
				(font
					(size 1.27 1.27)
				)
			)
		)
		(property "Value" ""
			(at 0 0 270)
			(layer "F.Fab")
			(effects
				(font
					(size 1.27 1.27)
				)
			)
		)
		(duplicate_pad_numbers_are_jumpers no)
		(fp_line
			(start -0.32512 0.175006)
			(end -0.32512 -0.175006)
			(stroke
				(width 0.1)
				(type default)
			)
			(layer "F.Fab")
		)
		(fp_line
			(start 0.32512 0.175006)
			(end -0.32512 0.175006)
			(stroke
				(width 0.1)
				(type default)
			)
			(layer "F.Fab")
		)
		(fp_line
			(start -0.32512 -0.175006)
			(end 0.32512 -0.175006)
			(stroke
				(width 0.1)
				(type default)
			)
			(layer "F.Fab")
		)
		(fp_line
			(start 0.32512 -0.175006)
			(end 0.32512 0.175006)
			(stroke
				(width 0.1)
				(type default)
			)
			(layer "F.Fab")
		)
		(pad "1" smd rect
			(at -0.2667 0 270)
			(size 0.3048 0.381)
			(layers "F.Cu" "F.Mask" "F.Paste")
			(net "JTAG_TEST_MODE_RT_CPU1_P1")
		)
		(pad "2" smd rect
			(at 0.2667 0 90)
			(size 0.3048 0.381)
			(layers "F.Cu" "F.Mask" "F.Paste")
			(net "GND")
		)
	)
	(footprint ""
		(layer "F.Cu")
		(at 459.158594 -46.264576 -90)
		(property "Reference" "PR834"
			(at 0 0 270)
			(layer "F.SilkS")
			(hide yes)
			(effects
				(font
					(size 1.27 1.27)
				)
			)
		)
		(property "Value" ""
			(at 0 0 270)
			(layer "F.Fab")
			(effects
				(font
					(size 1.27 1.27)
				)
			)
		)
		(duplicate_pad_numbers_are_jumpers no)
		(fp_line
			(start -0.7874 0.4064)
			(end -0.7874 -0.4064)
			(stroke
				(width 0.1524)
				(type default)
			)
			(layer "F.SilkS")
		)
		(fp_line
			(start 0.7874 0.4064)
			(end -0.7874 0.4064)
			(stroke
				(width 0.1524)
				(type default)
			)
			(layer "F.SilkS")
		)
		(fp_line
			(start -0.7874 -0.4064)
			(end 0.7874 -0.4064)
			(stroke
				(width 0.1524)
				(type default)
			)
			(layer "F.SilkS")
		)
		(fp_line
			(start 0.7874 -0.4064)
			(end 0.7874 0.4064)
			(stroke
				(width 0.1524)
				(type default)
			)
			(layer "F.SilkS")
		)
		(fp_line
			(start -0.67945 0.3048)
			(end -0.67945 -0.305054)
			(stroke
				(width 0.1)
				(type default)
			)
			(layer "F.Fab")
		)
		(fp_line
			(start -0.12065 0.3048)
			(end -0.67945 0.3048)
			(stroke
				(width 0.1)
				(type default)
			)
			(layer "F.Fab")
		)
		(fp_line
			(start 0.120396 0.3048)
			(end 0.120396 0.2794)
			(stroke
				(width 0.1)
				(type default)
			)
			(layer "F.Fab")
		)
		(fp_line
			(start 0.67945 0.3048)
			(end 0.120396 0.3048)
			(stroke
				(width 0.1)
				(type default)
			)
			(layer "F.Fab")
		)
		(fp_line
			(start -0.12065 0.2794)
			(end -0.12065 0.3048)
			(stroke
				(width 0.1)
				(type default)
			)
			(layer "F.Fab")
		)
		(fp_line
			(start 0.120396 0.2794)
			(end -0.12065 0.2794)
			(stroke
				(width 0.1)
				(type default)
			)
			(layer "F.Fab")
		)
		(fp_line
			(start -0.12065 -0.2794)
			(end 0.12065 -0.2794)
			(stroke
				(width 0.1)
				(type default)
			)
			(layer "F.Fab")
		)
		(fp_line
			(start 0.12065 -0.2794)
			(end 0.12065 -0.3048)
			(stroke
				(width 0.1)
				(type default)
			)
			(layer "F.Fab")
		)
		(fp_line
			(start 0.12065 -0.3048)
			(end 0.67945 -0.3048)
			(stroke
				(width 0.1)
				(type default)
			)
			(layer "F.Fab")
		)
		(fp_line
			(start 0.67945 -0.3048)
			(end 0.67945 0.3048)
			(stroke
				(width 0.1)
				(type default)
			)
			(layer "F.Fab")
		)
		(fp_line
			(start -0.67945 -0.305054)
			(end -0.12065 -0.305054)
			(stroke
				(width 0.1)
				(type default)
			)
			(layer "F.Fab")
		)
		(fp_line
			(start -0.12065 -0.305054)
			(end -0.12065 -0.2794)
			(stroke
				(width 0.1)
				(type default)
			)
			(layer "F.Fab")
		)
		(pad "1" smd circle
			(at -0.40005 0 270)
			(size 0 0)
			(layers "F.Cu" "F.Mask" "F.Paste")
			(net "P3V3_AUX_ILIM")
		)
		(pad "2" smd circle
			(at 0.40005 0 270)
			(size 0 0)
			(layers "F.Cu" "F.Mask" "F.Paste")
			(net "GND")
		)
	)
	(footprint ""
		(layer "F.Cu")
		(at 233.2228 -281.7368)
		(property "Reference" "PC6803"
			(at 0 0 0)
			(layer "F.SilkS")
			(hide yes)
			(effects
				(font
					(size 1.27 1.27)
				)
			)
		)
		(property "Value" ""
			(at 0 0 0)
			(layer "F.Fab")
			(effects
				(font
					(size 1.27 1.27)
				)
			)
		)
		(duplicate_pad_numbers_are_jumpers no)
		(fp_line
			(start -1.524 -0.762)
			(end 1.524 -0.762)
			(stroke
				(width 0.1524)
				(type default)
			)
			(layer "F.SilkS")
		)
		(fp_line
			(start -1.524 0.762)
			(end -1.524 -0.762)
			(stroke
				(width 0.1524)
				(type default)
			)
			(layer "F.SilkS")
		)
		(fp_line
			(start 1.524 -0.762)
			(end 1.524 0.762)
			(stroke
				(width 0.1524)
				(type default)
			)
			(layer "F.SilkS")
		)
		(fp_line
			(start 1.524 0.762)
			(end -1.524 0.762)
			(stroke
				(width 0.1524)
				(type default)
			)
			(layer "F.SilkS")
		)
		(fp_line
			(start -1.1049 -0.724916)
			(end -1.1049 0.724916)
			(stroke
				(width 0.1)
				(type default)
			)
			(layer "F.Fab")
		)
		(fp_line
			(start -1.1049 0.724916)
			(end 1.1049 0.724916)
			(stroke
				(width 0.1)
				(type default)
			)
			(layer "F.Fab")
		)
		(fp_line
			(start 1.1049 -0.724916)
			(end -1.1049 -0.724916)
			(stroke
				(width 0.1)
				(type default)
			)
			(layer "F.Fab")
		)
		(fp_line
			(start 1.1049 0.724916)
			(end 1.1049 -0.724916)
			(stroke
				(width 0.1)
				(type default)
			)
			(layer "F.Fab")
		)
		(pad "1" smd rect
			(at -0.889 0 180)
			(size 1.016 1.27)
			(layers "F.Cu" "F.Mask" "F.Paste")
			(net "SW_P12V_AUX_P1V8_RETIMER_CPU1_FLT")
		)
		(pad "2" smd rect
			(at 0.889 0 180)
			(size 1.016 1.27)
			(layers "F.Cu" "F.Mask" "F.Paste")
			(net "GND")
		)
	)
	(footprint ""
		(layer "F.Cu")
		(at 421.104568 -369.28044 90)
		(property "Reference" "R6857"
			(at 0 0 90)
			(layer "F.SilkS")
			(hide yes)
			(effects
				(font
					(size 1.27 1.27)
				)
			)
		)
		(property "Value" ""
			(at 0 0 90)
			(layer "F.Fab")
			(effects
				(font
					(size 1.27 1.27)
				)
			)
		)
		(duplicate_pad_numbers_are_jumpers no)
		(fp_line
			(start 0.7874 -0.4064)
			(end 0.7874 0.4064)
			(stroke
				(width 0.1524)
				(type default)
			)
			(layer "F.SilkS")
		)
		(fp_line
			(start -0.7874 -0.4064)
			(end 0.7874 -0.4064)
			(stroke
				(width 0.1524)
				(type default)
			)
			(layer "F.SilkS")
		)
		(fp_line
			(start 0.7874 0.4064)
			(end -0.7874 0.4064)
			(stroke
				(width 0.1524)
				(type default)
			)
			(layer "F.SilkS")
		)
		(fp_line
			(start -0.7874 0.4064)
			(end -0.7874 -0.4064)
			(stroke
				(width 0.1524)
				(type default)
			)
			(layer "F.SilkS")
		)
		(fp_line
			(start -0.12065 -0.305054)
			(end -0.12065 -0.2794)
			(stroke
				(width 0.1)
				(type default)
			)
			(layer "F.Fab")
		)
		(fp_line
			(start -0.67945 -0.305054)
			(end -0.12065 -0.305054)
			(stroke
				(width 0.1)
				(type default)
			)
			(layer "F.Fab")
		)
		(fp_line
			(start 0.67945 -0.3048)
			(end 0.67945 0.3048)
			(stroke
				(width 0.1)
				(type default)
			)
			(layer "F.Fab")
		)
		(fp_line
			(start 0.12065 -0.3048)
			(end 0.67945 -0.3048)
			(stroke
				(width 0.1)
				(type default)
			)
			(layer "F.Fab")
		)
		(fp_line
			(start 0.12065 -0.2794)
			(end 0.12065 -0.3048)
			(stroke
				(width 0.1)
				(type default)
			)
			(layer "F.Fab")
		)
		(fp_line
			(start -0.12065 -0.2794)
			(end 0.12065 -0.2794)
			(stroke
				(width 0.1)
				(type default)
			)
			(layer "F.Fab")
		)
		(fp_line
			(start 0.120396 0.2794)
			(end -0.12065 0.2794)
			(stroke
				(width 0.1)
				(type default)
			)
			(layer "F.Fab")
		)
		(fp_line
			(start -0.12065 0.2794)
			(end -0.12065 0.3048)
			(stroke
				(width 0.1)
				(type default)
			)
			(layer "F.Fab")
		)
		(fp_line
			(start 0.67945 0.3048)
			(end 0.120396 0.3048)
			(stroke
				(width 0.1)
				(type default)
			)
			(layer "F.Fab")
		)
		(fp_line
			(start 0.120396 0.3048)
			(end 0.120396 0.2794)
			(stroke
				(width 0.1)
				(type default)
			)
			(layer "F.Fab")
		)
		(fp_line
			(start -0.12065 0.3048)
			(end -0.67945 0.3048)
			(stroke
				(width 0.1)
				(type default)
			)
			(layer "F.Fab")
		)
		(fp_line
			(start -0.67945 0.3048)
			(end -0.67945 -0.305054)
			(stroke
				(width 0.1)
				(type default)
			)
			(layer "F.Fab")
		)
		(pad "1" smd circle
			(at -0.40005 0 90)
			(size 0 0)
			(layers "F.Cu" "F.Mask" "F.Paste")
			(net "SMB_SCM_2_R6_SDA")
		)
		(pad "2" smd circle
			(at 0.40005 0 90)
			(size 0 0)
			(layers "F.Cu" "F.Mask" "F.Paste")
			(net "P0V9_RETIMER_CPU0_PMSDA")
		)
	)
	(footprint ""
		(layer "F.Cu")
		(at 302.241458 -110.795308)
		(property "Reference" "R52"
			(at 0 0 0)
			(layer "F.SilkS")
			(hide yes)
			(effects
				(font
					(size 1.27 1.27)
				)
			)
		)
		(property "Value" ""
			(at 0 0 0)
			(layer "F.Fab")
			(effects
				(font
					(size 1.27 1.27)
				)
			)
		)
		(duplicate_pad_numbers_are_jumpers no)
		(fp_line
			(start -0.7874 -0.4064)
			(end 0.7874 -0.4064)
			(stroke
				(width 0.1524)
				(type default)
			)
			(layer "F.SilkS")
		)
		(fp_line
			(start -0.7874 0.4064)
			(end -0.7874 -0.4064)
			(stroke
				(width 0.1524)
				(type default)
			)
			(layer "F.SilkS")
		)
		(fp_line
			(start 0.7874 -0.4064)
			(end 0.7874 0.4064)
			(stroke
				(width 0.1524)
				(type default)
			)
			(layer "F.SilkS")
		)
		(fp_line
			(start 0.7874 0.4064)
			(end -0.7874 0.4064)
			(stroke
				(width 0.1524)
				(type default)
			)
			(layer "F.SilkS")
		)
		(fp_line
			(start -0.67945 -0.305054)
			(end -0.12065 -0.305054)
			(stroke
				(width 0.1)
				(type default)
			)
			(layer "F.Fab")
		)
		(fp_line
			(start -0.67945 0.3048)
			(end -0.67945 -0.305054)
			(stroke
				(width 0.1)
				(type default)
			)
			(layer "F.Fab")
		)
		(fp_line
			(start -0.12065 -0.305054)
			(end -0.12065 -0.2794)
			(stroke
				(width 0.1)
				(type default)
			)
			(layer "F.Fab")
		)
		(fp_line
			(start -0.12065 -0.2794)
			(end 0.12065 -0.2794)
			(stroke
				(width 0.1)
				(type default)
			)
			(layer "F.Fab")
		)
		(fp_line
			(start -0.12065 0.2794)
			(end -0.12065 0.3048)
			(stroke
				(width 0.1)
				(type default)
			)
			(layer "F.Fab")
		)
		(fp_line
			(start -0.12065 0.3048)
			(end -0.67945 0.3048)
			(stroke
				(width 0.1)
				(type default)
			)
			(layer "F.Fab")
		)
		(fp_line
			(start 0.120396 0.2794)
			(end -0.12065 0.2794)
			(stroke
				(width 0.1)
				(type default)
			)
			(layer "F.Fab")
		)
		(fp_line
			(start 0.120396 0.3048)
			(end 0.120396 0.2794)
			(stroke
				(width 0.1)
				(type default)
			)
			(layer "F.Fab")
		)
		(fp_line
			(start 0.12065 -0.3048)
			(end 0.67945 -0.3048)
			(stroke
				(width 0.1)
				(type default)
			)
			(layer "F.Fab")
		)
		(fp_line
			(start 0.12065 -0.2794)
			(end 0.12065 -0.3048)
			(stroke
				(width 0.1)
				(type default)
			)
			(layer "F.Fab")
		)
		(fp_line
			(start 0.67945 -0.3048)
			(end 0.67945 0.3048)
			(stroke
				(width 0.1)
				(type default)
			)
			(layer "F.Fab")
		)
		(fp_line
			(start 0.67945 0.3048)
			(end 0.120396 0.3048)
			(stroke
				(width 0.1)
				(type default)
			)
			(layer "F.Fab")
		)
		(pad "1" smd circle
			(at -0.40005 0)
			(size 0 0)
			(layers "F.Cu" "F.Mask" "F.Paste")
			(net "P3V3_AUX")
		)
		(pad "2" smd circle
			(at 0.40005 0)
			(size 0 0)
			(layers "F.Cu" "F.Mask" "F.Paste")
			(net "CPU_FRU_ADDR2")
		)
	)
	(footprint ""
		(layer "F.Cu")
		(at 105.64876 -61.087254 180)
		(property "Reference" "R1741"
			(at 0 0 180)
			(layer "F.SilkS")
			(hide yes)
			(effects
				(font
					(size 1.27 1.27)
				)
			)
		)
		(property "Value" ""
			(at 0 0 180)
			(layer "F.Fab")
			(effects
				(font
					(size 1.27 1.27)
				)
			)
		)
		(duplicate_pad_numbers_are_jumpers no)
		(fp_line
			(start 0.7874 0.4064)
			(end -0.7874 0.4064)
			(stroke
				(width 0.1524)
				(type default)
			)
			(layer "F.SilkS")
		)
		(fp_line
			(start 0.7874 -0.4064)
			(end 0.7874 0.4064)
			(stroke
				(width 0.1524)
				(type default)
			)
			(layer "F.SilkS")
		)
		(fp_line
			(start -0.7874 0.4064)
			(end -0.7874 -0.4064)
			(stroke
				(width 0.1524)
				(type default)
			)
			(layer "F.SilkS")
		)
		(fp_line
			(start -0.7874 -0.4064)
			(end 0.7874 -0.4064)
			(stroke
				(width 0.1524)
				(type default)
			)
			(layer "F.SilkS")
		)
		(fp_line
			(start 0.67945 0.3048)
			(end 0.120396 0.3048)
			(stroke
				(width 0.1)
				(type default)
			)
			(layer "F.Fab")
		)
		(fp_line
			(start 0.67945 -0.3048)
			(end 0.67945 0.3048)
			(stroke
				(width 0.1)
				(type default)
			)
			(layer "F.Fab")
		)
		(fp_line
			(start 0.12065 -0.2794)
			(end 0.12065 -0.3048)
			(stroke
				(width 0.1)
				(type default)
			)
			(layer "F.Fab")
		)
		(fp_line
			(start 0.12065 -0.3048)
			(end 0.67945 -0.3048)
			(stroke
				(width 0.1)
				(type default)
			)
			(layer "F.Fab")
		)
		(fp_line
			(start 0.120396 0.3048)
			(end 0.120396 0.2794)
			(stroke
				(width 0.1)
				(type default)
			)
			(layer "F.Fab")
		)
		(fp_line
			(start 0.120396 0.2794)
			(end -0.12065 0.2794)
			(stroke
				(width 0.1)
				(type default)
			)
			(layer "F.Fab")
		)
		(fp_line
			(start -0.12065 0.3048)
			(end -0.67945 0.3048)
			(stroke
				(width 0.1)
				(type default)
			)
			(layer "F.Fab")
		)
		(fp_line
			(start -0.12065 0.2794)
			(end -0.12065 0.3048)
			(stroke
				(width 0.1)
				(type default)
			)
			(layer "F.Fab")
		)
		(fp_line
			(start -0.12065 -0.2794)
			(end 0.12065 -0.2794)
			(stroke
				(width 0.1)
				(type default)
			)
			(layer "F.Fab")
		)
		(fp_line
			(start -0.12065 -0.305054)
			(end -0.12065 -0.2794)
			(stroke
				(width 0.1)
				(type default)
			)
			(layer "F.Fab")
		)
		(fp_line
			(start -0.67945 0.3048)
			(end -0.67945 -0.305054)
			(stroke
				(width 0.1)
				(type default)
			)
			(layer "F.Fab")
		)
		(fp_line
			(start -0.67945 -0.305054)
			(end -0.12065 -0.305054)
			(stroke
				(width 0.1)
				(type default)
			)
			(layer "F.Fab")
		)
		(pad "1" smd circle
			(at -0.40005 0 180)
			(size 0 0)
			(layers "F.Cu" "F.Mask" "F.Paste")
			(net "JTAG_SCM_PLD_R_TMS")
		)
		(pad "2" smd circle
			(at 0.40005 0 180)
			(size 0 0)
			(layers "F.Cu" "F.Mask" "F.Paste")
			(net "JTAG_SCM_PLD_TMS")
		)
	)
	(footprint ""
		(layer "F.Cu")
		(at 328.092308 -103.66375)
		(property "Reference" "C1107"
			(at 0 0 0)
			(layer "F.SilkS")
			(hide yes)
			(effects
				(font
					(size 1.27 1.27)
				)
			)
		)
		(property "Value" ""
			(at 0 0 0)
			(layer "F.Fab")
			(effects
				(font
					(size 1.27 1.27)
				)
			)
		)
		(duplicate_pad_numbers_are_jumpers no)
		(fp_line
			(start -0.7874 -0.4064)
			(end 0.7874 -0.4064)
			(stroke
				(width 0.1524)
				(type default)
			)
			(layer "F.SilkS")
		)
		(fp_line
			(start -0.7874 0.4064)
			(end -0.7874 -0.4064)
			(stroke
				(width 0.1524)
				(type default)
			)
			(layer "F.SilkS")
		)
		(fp_line
			(start 0.7874 -0.4064)
			(end 0.7874 0.4064)
			(stroke
				(width 0.1524)
				(type default)
			)
			(layer "F.SilkS")
		)
		(fp_line
			(start 0.7874 0.4064)
			(end -0.7874 0.4064)
			(stroke
				(width 0.1524)
				(type default)
			)
			(layer "F.SilkS")
		)
		(fp_line
			(start -0.67945 -0.305054)
			(end -0.12065 -0.305054)
			(stroke
				(width 0.1)
				(type default)
			)
			(layer "F.Fab")
		)
		(fp_line
			(start -0.67945 0.3048)
			(end -0.67945 -0.305054)
			(stroke
				(width 0.1)
				(type default)
			)
			(layer "F.Fab")
		)
		(fp_line
			(start -0.12065 -0.305054)
			(end -0.12065 -0.2794)
			(stroke
				(width 0.1)
				(type default)
			)
			(layer "F.Fab")
		)
		(fp_line
			(start -0.12065 -0.2794)
			(end 0.12065 -0.2794)
			(stroke
				(width 0.1)
				(type default)
			)
			(layer "F.Fab")
		)
		(fp_line
			(start -0.12065 0.2794)
			(end -0.12065 0.3048)
			(stroke
				(width 0.1)
				(type default)
			)
			(layer "F.Fab")
		)
		(fp_line
			(start -0.12065 0.3048)
			(end -0.67945 0.3048)
			(stroke
				(width 0.1)
				(type default)
			)
			(layer "F.Fab")
		)
		(fp_line
			(start 0.120396 0.2794)
			(end -0.12065 0.2794)
			(stroke
				(width 0.1)
				(type default)
			)
			(layer "F.Fab")
		)
		(fp_line
			(start 0.120396 0.3048)
			(end 0.120396 0.2794)
			(stroke
				(width 0.1)
				(type default)
			)
			(layer "F.Fab")
		)
		(fp_line
			(start 0.12065 -0.3048)
			(end 0.67945 -0.3048)
			(stroke
				(width 0.1)
				(type default)
			)
			(layer "F.Fab")
		)
		(fp_line
			(start 0.12065 -0.2794)
			(end 0.12065 -0.3048)
			(stroke
				(width 0.1)
				(type default)
			)
			(layer "F.Fab")
		)
		(fp_line
			(start 0.67945 -0.3048)
			(end 0.67945 0.3048)
			(stroke
				(width 0.1)
				(type default)
			)
			(layer "F.Fab")
		)
		(fp_line
			(start 0.67945 0.3048)
			(end 0.120396 0.3048)
			(stroke
				(width 0.1)
				(type default)
			)
			(layer "F.Fab")
		)
		(pad "1" smd circle
			(at -0.40005 0)
			(size 0 0)
			(layers "F.Cu" "F.Mask" "F.Paste")
			(net "P12V_E1S_0")
		)
		(pad "2" smd circle
			(at 0.40005 0)
			(size 0 0)
			(layers "F.Cu" "F.Mask" "F.Paste")
			(net "GND")
		)
	)
	(footprint ""
		(layer "F.Cu")
		(at 367.787936 -402.548852 -90)
		(property "Reference" "R1104"
			(at 0 0 270)
			(layer "F.SilkS")
			(hide yes)
			(effects
				(font
					(size 1.27 1.27)
				)
			)
		)
		(property "Value" ""
			(at 0 0 270)
			(layer "F.Fab")
			(effects
				(font
					(size 1.27 1.27)
				)
			)
		)
		(duplicate_pad_numbers_are_jumpers no)
		(fp_line
			(start -0.32512 0.175006)
			(end -0.32512 -0.175006)
			(stroke
				(width 0.1)
				(type default)
			)
			(layer "F.Fab")
		)
		(fp_line
			(start 0.32512 0.175006)
			(end -0.32512 0.175006)
			(stroke
				(width 0.1)
				(type default)
			)
			(layer "F.Fab")
		)
		(fp_line
			(start -0.32512 -0.175006)
			(end 0.32512 -0.175006)
			(stroke
				(width 0.1)
				(type default)
			)
			(layer "F.Fab")
		)
		(fp_line
			(start 0.32512 -0.175006)
			(end 0.32512 0.175006)
			(stroke
				(width 0.1)
				(type default)
			)
			(layer "F.Fab")
		)
		(pad "1" smd rect
			(at -0.2667 0 270)
			(size 0.3048 0.381)
			(layers "F.Cu" "F.Mask" "F.Paste")
			(net "RST_RT_CPU0_P3_RESET_R_N")
		)
		(pad "2" smd rect
			(at 0.2667 0 90)
			(size 0.3048 0.381)
			(layers "F.Cu" "F.Mask" "F.Paste")
			(net "GND")
		)
	)
)
